# S9S_MB_2U (Grand Teton) — schematic netlist excerpt (pin names and nets, part order shuffled) for the footprints in the layout excerpt that follows; sources: Cadence DE-HDL packaged netlist, KiCad conversion of 03242023_DA0F0TMBIJ0_F0T_Motherboard_J_brd_V01_OCP.brd

J18  SCONN288_ADR50017P087CC  SCONN288_ADR50017-P087CC IO  pkg DDR288S_1-1VXB  page 99
  VIN_BULK0  = P12V_S3_AUX_CPU1_NVDIMM
  RFU0  = TP_CHA_CPU1_DIMM2_FRU_0
  VIN_MGMT  = P3V3_AUX
  HSCL  = I3C_SPD_DDRABCD_CPU1_LVC1_SCL_1
  HSDA  = I3C_SPD_DDRABCD_CPU1_LVC1_SDA
  VSS0  = GND
  DQ0_A  = M_A_CPU1_SA_DQ<0>
  VSS1  = GND
  DQ1_A  = M_A_CPU1_SA_DQ<1>
  VSS2  = GND
  DQS0_A_T  = M_A_CPU1_SA_DQS_DP<0>
  DQS0_A_C  = M_A_CPU1_SA_DQS_DN<0>
  VSS3  = GND
  DQ4_A  = M_A_CPU1_SA_DQ<4>
  VSS4  = GND
  DQ5_A  = M_A_CPU1_SA_DQ<5>
  VSS5  = GND
  DQ8_A  = M_A_CPU1_SA_DQ<8>
  VSS6  = GND
  DQ9_A  = M_A_CPU1_SA_DQ<9>
  VSS7  = GND
  DQS1_A_T  = M_A_CPU1_SA_DQS_DP<1>
  DQS1_A_C  = M_A_CPU1_SA_DQS_DN<1>
  VSS8  = GND
  DQ12_A  = M_A_CPU1_SA_DQ<12>
  VSS9  = GND
  DQ13_A  = M_A_CPU1_SA_DQ<13>
  VSS10  = GND
  DQ16_A  = M_A_CPU1_SA_DQ<16>
  VSS11  = GND
  DQ17_A  = M_A_CPU1_SA_DQ<17>
  VSS12  = GND
  DQS2_A_T  = M_A_CPU1_SA_DQS_DP<2>
  DQS2_A_C  = M_A_CPU1_SA_DQS_DN<2>
  VSS13  = GND
  DQ20_A  = M_A_CPU1_SA_DQ<20>
  VSS14  = GND
  DQ21_A  = M_A_CPU1_SA_DQ<21>
  VSS15  = GND
  DQ24_A  = M_A_CPU1_SA_DQ<24>
  VSS16  = GND
  DQ25_A  = M_A_CPU1_SA_DQ<25>
  VSS17  = GND
  DQS3_A_T  = M_A_CPU1_SA_DQS_DP<3>
  DQS3_A_C  = M_A_CPU1_SA_DQS_DN<3>
  VSS18  = GND
  DQ28_A  = M_A_CPU1_SA_DQ<28>
  VSS19  = GND
  DQ29_A  = M_A_CPU1_SA_DQ<29>
  VSS20  = GND
  CB0_A  = M_A_CPU1_SA_CB<0>
  VSS21  = GND
  CB1_A  = M_A_CPU1_SA_CB<1>
  VSS22  = GND
  DQS4_A_T  = M_A_CPU1_SA_DQS_DP<4>
  DQS4_A_C  = M_A_CPU1_SA_DQS_DN<4>
  VSS23  = GND
  CB4_A  = M_A_CPU1_SA_CB<4>
  VSS24  = GND
  CB5_A  = M_A_CPU1_SA_CB<5>
  VSS25  = GND
  ALERT_N  = M_A_CPU1_ALERT_N
  VSS26  = GND
  CS0_A_N  = M_A_CPU1_SA_CS_N<2>
  VSS27  = GND
  CA0_A  = M_A_CPU1_SA_CA<0>
  VSS28  = GND
  CA2_A  = M_A_CPU1_SA_CA<2>
  VSS29  = GND
  CA4_A  = M_A_CPU1_SA_CA<4>
  VSS30  = GND
  CA6_A  = M_A_CPU1_SA_CA<6>
  VSS31  = GND
  PAR_A  = M_A_CPU1_SA_PAR
  VSS32  = GND
  CA0_B  = M_A_CPU1_SB_CA<0>
  VSS33  = GND
  CA2_B  = M_A_CPU1_SB_CA<2>
  VSS34  = GND
  CA4_B  = M_A_CPU1_SB_CA<4>
  VSS35  = GND
  CA6_B  = M_A_CPU1_SB_CA<6>
  VSS36  = GND
  CS0_B_N  = M_A_CPU1_SB_CS_N<2>
  VSS37  = GND
  \lbd||rsp_a_n\  = M_A_CPU1_SA_RSP<1>
  \lbs||rsp_b_n\  = M_A_CPU1_SB_RSP<1>
  VSS38  = GND
  CB4_B  = M_A_CPU1_SB_CB<4>
  VSS39  = GND
  CB5_B  = M_A_CPU1_SB_CB<5>
  VSS40  = GND
  \dqs9_b_t||tdqs9_b_t||dbi4_b_n\  = M_A_CPU1_SB_DQS_DP<9>
  \dqs9_b_c||tdqs9_b_c\  = M_A_CPU1_SB_DQS_DN<9>
  VSS41  = GND
  CB0_B  = M_A_CPU1_SB_CB<0>
  VSS42  = GND
  CB1_B  = M_A_CPU1_SB_CB<1>
  VSS43  = GND
  DQ0_B  = M_A_CPU1_SB_DQ<0>
  VSS44  = GND
  DQ1_B  = M_A_CPU1_SB_DQ<1>
  VSS45  = GND
  DQS0_B_T  = M_A_CPU1_SB_DQS_DP<0>
  DQS0_B_C  = M_A_CPU1_SB_DQS_DN<0>
  VSS46  = GND
  DQ4_B  = M_A_CPU1_SB_DQ<4>
  VSS47  = GND
  DQ5_B  = M_A_CPU1_SB_DQ<5>
  VSS48  = GND
  DQ8_B  = M_A_CPU1_SB_DQ<8>
  VSS49  = GND
  DQ9_B  = M_A_CPU1_SB_DQ<9>
  VSS50  = GND
  DQS1_B_T  = M_A_CPU1_SB_DQS_DP<1>
  DQS1_B_C  = M_A_CPU1_SB_DQS_DN<1>
  VSS51  = GND
  DQ12_B  = M_A_CPU1_SB_DQ<12>
  VSS52  = GND
  DQ13_B  = M_A_CPU1_SB_DQ<13>
  VSS53  = GND
  DQ16_B  = M_A_CPU1_SB_DQ<16>
  VSS54  = GND
  DQ17_B  = M_A_CPU1_SB_DQ<17>
  VSS55  = GND
  DQS2_B_T  = M_A_CPU1_SB_DQS_DP<2>
  DQS2_B_C  = M_A_CPU1_SB_DQS_DN<2>
  VSS56  = GND
  DQ20_B  = M_A_CPU1_SB_DQ<20>
  VSS57  = GND
  DQ21_B  = M_A_CPU1_SB_DQ<21>
  VSS58  = GND
  DQ24_B  = M_A_CPU1_SB_DQ<24>
  VSS59  = GND
  DQ25_B  = M_A_CPU1_SB_DQ<25>
  VSS60  = GND
  DQS3_B_T  = M_A_CPU1_SB_DQS_DP<3>
  DQS3_B_C  = M_A_CPU1_SB_DQS_DN<3>
  VSS61  = GND
  DQ28_B  = M_A_CPU1_SB_DQ<28>
  VSS62  = GND
  DQ29_B  = M_A_CPU1_SB_DQ<29>
  VSS63  = GND
  RFU1  = TP_CHA_CPU1_DIMM2_FRU_1
  VIN_BULK1  = P12V_S3_AUX_CPU1_NVDIMM
  VIN_BULK2  = P12V_S3_AUX_CPU1_NVDIMM
  \pwr_good||fail_n\  = PWRGD_CHA_CPU1_DIMM2
  HSA  = PD_CHA_CPU1_DIMM2_SAA
  RFU2  = TP_CHA_CPU1_DIMM2_FRU_2
  RFU3  = TP_CHA_CPU1_DIMM2_FRU_3
  VSS64  = GND
  DQ2_A  = M_A_CPU1_SA_DQ<2>
  VSS65  = GND
  DQ3_A  = M_A_CPU1_SA_DQ<3>
  VSS66  = GND
  \dqs5_a_c||tdqs5_a_c||dqs5_a_t||tdqs5_a_t\  = M_A_CPU1_SA_DQS_DN<5>
  \dqs5_a_t||tdqs5_a_t\  = M_A_CPU1_SA_DQS_DP<5>
  VSS67  = GND
  DQ6_A  = M_A_CPU1_SA_DQ<6>
  VSS68  = GND
  DQ7_A  = M_A_CPU1_SA_DQ<7>
  VSS69  = GND
  DQ10_A  = M_A_CPU1_SA_DQ<10>
  VSS70  = GND
  DQ11_A  = M_A_CPU1_SA_DQ<11>
  VSS71  = GND
  \dqs6_a_c||tdqs6_a_c||dqs6_a_t||tdqs6_a_t\  = M_A_CPU1_SA_DQS_DN<6>
  \dqs6_a_t||tdqs6_a_t\  = M_A_CPU1_SA_DQS_DP<6>
  VSS72  = GND
  DQ14_A  = M_A_CPU1_SA_DQ<14>
  VSS73  = GND
  DQ15_A  = M_A_CPU1_SA_DQ<15>
  VSS74  = GND
  DQ18_A  = M_A_CPU1_SA_DQ<18>
  VSS75  = GND
  DQ19_A  = M_A_CPU1_SA_DQ<19>
  VSS76  = GND
  \dqs7_a_c||tdqs7_a_c\  = M_A_CPU1_SA_DQS_DN<7>
  \dqs7_a_t||tdqs7_a_t\  = M_A_CPU1_SA_DQS_DP<7>
  VSS77  = GND
  DQ22_A  = M_A_CPU1_SA_DQ<22>
  VSS78  = GND
  DQ23_A  = M_A_CPU1_SA_DQ<23>
  VSS79  = GND
  DQ26_A  = M_A_CPU1_SA_DQ<26>
  VSS80  = GND
  DQ27_A  = M_A_CPU1_SA_DQ<27>
  VSS81  = GND
  \dqs8_a_c||tdqs8_a_c\  = M_A_CPU1_SA_DQS_DN<8>
  \dqs8_a_t||tdqs8_a_t\  = M_A_CPU1_SA_DQS_DP<8>
  VSS82  = GND
  DQ30_A  = M_A_CPU1_SA_DQ<30>
  VSS83  = GND
  DQ31_A  = M_A_CPU1_SA_DQ<31>
  VSS84  = GND
  CB2_A  = M_A_CPU1_SA_CB<2>
  VSS85  = GND
  CB3_A  = M_A_CPU1_SA_CB<3>
  VSS86  = GND
  \dqs9_a_c||tdqs9_a_c\  = M_A_CPU1_SA_DQS_DN<9>
  \dqs9_a_t||tdqs9_a_t\  = M_A_CPU1_SA_DQS_DP<9>
  VSS87  = GND
  CB6_A  = M_A_CPU1_SA_CB<6>
  VSS88  = GND
  CB7_A  = M_A_CPU1_SA_CB<7>
  VSS89  = GND
  RESET_N  = RST_M_AB_CPU1_FPGA_N
  VSS90  = GND
  CS1_A_N  = M_A_CPU1_SA_CS_N<3>
  VSS91  = GND
  CA1_A  = M_A_CPU1_SA_CA<1>
  VSS92  = GND
  CA3_A  = M_A_CPU1_SA_CA<3>
  VSS93  = GND
  CA5_A  = M_A_CPU1_SA_CA<5>
  VSS94  = GND
  CK_T  = M_A_CPU1_CLK_DP<1>
  CK_C  = M_A_CPU1_CLK_DN<1>
  VSS95  = GND
  RFU4  = TP_CHA_CPU1_DIMM2_FRU_4
  CA1_B  = M_A_CPU1_SB_CA<1>
  VSS96  = GND
  CA3_B  = M_A_CPU1_SB_CA<3>
  VSS97  = GND
  CA5_B  = M_A_CPU1_SB_CA<5>
  VSS98  = GND
  PAR_B  = M_A_CPU1_SB_PAR
  VSS99  = GND
  CS1_B_N  = M_A_CPU1_SB_CS_N<3>
  VSS100  = GND
  RFU5  = TP_CHA_CPU1_DIMM2_FRU_5
  RFU6  = TP_CHA_CPU1_DIMM2_FRU_6
  VSS101  = GND
  CB6_B  = M_A_CPU1_SB_CB<6>
  VSS102  = GND
  CB7_B  = M_A_CPU1_SB_CB<7>
  VSS103  = GND
  DQS4_B_C  = M_A_CPU1_SB_DQS_DN<4>
  DQS4_B_T  = M_A_CPU1_SB_DQS_DP<4>
  VSS104  = GND
  CB2_B  = M_A_CPU1_SB_CB<2>
  VSS105  = GND
  CB3_B  = M_A_CPU1_SB_CB<3>
  VSS106  = GND
  DQ2_B  = M_A_CPU1_SB_DQ<2>
  VSS107  = GND
  DQ3_B  = M_A_CPU1_SB_DQ<3>
  VSS108  = GND
  \dqs5_b_c||tdqs5_b_c\  = M_A_CPU1_SB_DQS_DN<5>
  \dqs5_b_t||tdqs5_b_t\  = M_A_CPU1_SB_DQS_DP<5>
  VSS109  = GND
  DQ6_B  = M_A_CPU1_SB_DQ<6>
  VSS110  = GND
  DQ7_B  = M_A_CPU1_SB_DQ<7>
  VSS111  = GND
  DQ10_B  = M_A_CPU1_SB_DQ<10>
  VSS112  = GND
  DQ11_B  = M_A_CPU1_SB_DQ<11>
  VSS113  = GND
  \dqs6_b_c||tdqs6_b_c\  = M_A_CPU1_SB_DQS_DN<6>
  \dqs6_b_t||tdqs6_b_t\  = M_A_CPU1_SB_DQS_DP<6>
  VSS114  = GND
  DQ14_B  = M_A_CPU1_SB_DQ<14>
  VSS115  = GND
  DQ15_B  = M_A_CPU1_SB_DQ<15>
  VSS116  = GND
  DQ18_B  = M_A_CPU1_SB_DQ<18>
  VSS117  = GND
  DQ19_B  = M_A_CPU1_SB_DQ<19>
  VSS118  = GND
  \dqs7_b_c||tdqs7_b_c\  = M_A_CPU1_SB_DQS_DN<7>
  \dqs7_b_t||tdqs7_b_t\  = M_A_CPU1_SB_DQS_DP<7>
  VSS119  = GND
  DQ22_B  = M_A_CPU1_SB_DQ<22>
  VSS120  = GND
  DQ23_B  = M_A_CPU1_SB_DQ<23>
  VSS121  = GND
  DQ26_B  = M_A_CPU1_SB_DQ<26>
  VSS122  = GND
  DQ27_B  = M_A_CPU1_SB_DQ<27>
  VSS123  = GND
  \dqs8_b_c||tdqs8_b_c\  = M_A_CPU1_SB_DQS_DN<8>
  \dqs8_b_t||tdqs8_b_t\  = M_A_CPU1_SB_DQS_DP<8>
  VSS124  = GND
  DQ30_B  = M_A_CPU1_SB_DQ<30>
  VSS125  = GND
  DQ31_B  = M_A_CPU1_SB_DQ<31>
  VSS126  = GND
  G1  = GND
  G2  = GND
  G3  = GND

(kicad_pcb
	(version 20260206)
	(generator "pcbnew")
	(generator_version "10.0")
	(general
		(thickness 1.6)
		(legacy_teardrops no)
	)
	(paper "A4")
	(title_block
		(title "03242023_DA0F0TMBIJ0_F0T_Motherboard_J_brd_V01_OCP.brd")
		(comment 1 "Grand Teton / footprint 3819 of 6105 (J18), pads 229-274 of 291")
	)
	(layers
		(0 "F.Cu" signal "TOP")
		(4 "In1.Cu" signal "GND")
		(6 "In2.Cu" signal "IN1")
		(8 "In3.Cu" signal "GND1")
		(10 "In4.Cu" signal "IN2")
		(12 "In5.Cu" signal "GND2")
		(14 "In6.Cu" signal "IN3")
		(16 "In7.Cu" signal "GND3")
		(18 "In8.Cu" signal "VCC")
		(20 "In9.Cu" signal "VCC1")
		(22 "In10.Cu" signal "GND4")
		(24 "In11.Cu" signal "IN4")
		(26 "In12.Cu" signal "GND5")
		(28 "In13.Cu" signal "IN5")
		(30 "In14.Cu" signal "GND6")
		(32 "In15.Cu" signal "IN6")
		(34 "In16.Cu" signal "GND7")
		(2 "B.Cu" signal "BOTTOM")
		(9 "F.Adhes" user "F.Adhesive")
		(11 "B.Adhes" user "B.Adhesive")
		(13 "F.Paste" user "Package Geometry/Pastemask Top")
		(15 "B.Paste" user "Package Geometry/Pastemask Bottom")
		(5 "F.SilkS" user "Ref Des/Silkscreen Top")
		(7 "B.SilkS" user "Ref Des/Silkscreen Bottom")
		(1 "F.Mask" user "Board Geometry/Soldermask Top")
		(3 "B.Mask" user "Board Geometry/Soldermask Bottom")
		(17 "Dwgs.User" user "User.Drawings")
		(19 "Cmts.User" user "User.Comments")
		(21 "Eco1.User" user "User.Eco1")
		(23 "Eco2.User" user "User.Eco2")
		(25 "Edge.Cuts" user "Board Geometry/Outline")
		(27 "Margin" user)
		(31 "F.CrtYd" user "Package Geometry/Place Bound Top")
		(29 "B.CrtYd" user "Package Geometry/Place Bound Bottom")
		(35 "F.Fab" user "Ref Des/Assembly Top")
		(33 "B.Fab" user "Ref Des/Assembly Bottom")
	)
	(footprint ""
		(layer "F.Cu")
		(at 62.99708 -258.091686)
		(property "Reference" "J18"
			(at -1.547622 -81.836514 0)
			(unlocked yes)
			(layer "F.SilkS")
			(effects
				(font
					(size 0.7874 0.5842)
					(thickness 0.1524)
				)
				(justify left)
			)
		)
		(property "Value" ""
			(at 0 0 0)
			(layer "F.Fab")
			(effects
				(font
					(size 1.27 1.27)
				)
			)
		)
		(duplicate_pad_numbers_are_jumpers no)
		(pad "229" smd rect
			(at 2.050034 13.17498 270)
			(size 0.519938 1.4986)
			(layers "F.Cu" "F.Mask" "F.Paste")
			(net "M_A_CPU1_SB_CS_N<3>")
		)
		(pad "230" smd rect
			(at 2.050034 14.025118 270)
			(size 0.519938 1.4986)
			(layers "F.Cu" "F.Mask" "F.Paste")
			(net "GND")
		)
		(pad "231" smd rect
			(at 2.050034 14.875002 270)
			(size 0.519938 1.4986)
			(layers "F.Cu" "F.Mask" "F.Paste")
			(net "TP_CHA_CPU1_DIMM2_FRU_5")
		)
		(pad "232" smd rect
			(at 2.050034 15.724886 270)
			(size 0.519938 1.4986)
			(layers "F.Cu" "F.Mask" "F.Paste")
			(net "TP_CHA_CPU1_DIMM2_FRU_6")
		)
		(pad "233" smd rect
			(at 2.050034 16.575024 270)
			(size 0.519938 1.4986)
			(layers "F.Cu" "F.Mask" "F.Paste")
			(net "GND")
		)
		(pad "234" smd rect
			(at 2.050034 17.424908 270)
			(size 0.519938 1.4986)
			(layers "F.Cu" "F.Mask" "F.Paste")
			(net "M_A_CPU1_SB_CB<6>")
		)
		(pad "235" smd rect
			(at 2.050034 18.275046 270)
			(size 0.519938 1.4986)
			(layers "F.Cu" "F.Mask" "F.Paste")
			(net "GND")
		)
		(pad "236" smd rect
			(at 2.050034 19.12493 270)
			(size 0.519938 1.4986)
			(layers "F.Cu" "F.Mask" "F.Paste")
			(net "M_A_CPU1_SB_CB<7>")
		)
		(pad "237" smd rect
			(at 2.050034 19.975068 270)
			(size 0.519938 1.4986)
			(layers "F.Cu" "F.Mask" "F.Paste")
			(net "GND")
		)
		(pad "238" smd rect
			(at 2.050034 20.824952 270)
			(size 0.519938 1.4986)
			(layers "F.Cu" "F.Mask" "F.Paste")
			(net "M_A_CPU1_SB_DQS_DN<4>")
		)
		(pad "239" smd rect
			(at 2.050034 21.67509 270)
			(size 0.519938 1.4986)
			(layers "F.Cu" "F.Mask" "F.Paste")
			(net "M_A_CPU1_SB_DQS_DP<4>")
		)
		(pad "240" smd rect
			(at 2.050034 22.524974 270)
			(size 0.519938 1.4986)
			(layers "F.Cu" "F.Mask" "F.Paste")
			(net "GND")
		)
		(pad "241" smd rect
			(at 2.050034 23.375112 270)
			(size 0.519938 1.4986)
			(layers "F.Cu" "F.Mask" "F.Paste")
			(net "M_A_CPU1_SB_CB<2>")
		)
		(pad "242" smd rect
			(at 2.050034 24.224996 270)
			(size 0.519938 1.4986)
			(layers "F.Cu" "F.Mask" "F.Paste")
			(net "GND")
		)
		(pad "243" smd rect
			(at 2.050034 25.07488 270)
			(size 0.519938 1.4986)
			(layers "F.Cu" "F.Mask" "F.Paste")
			(net "M_A_CPU1_SB_CB<3>")
		)
		(pad "244" smd rect
			(at 2.050034 25.925018 270)
			(size 0.519938 1.4986)
			(layers "F.Cu" "F.Mask" "F.Paste")
			(net "GND")
		)
		(pad "245" smd rect
			(at 2.050034 26.774902 270)
			(size 0.519938 1.4986)
			(layers "F.Cu" "F.Mask" "F.Paste")
			(net "M_A_CPU1_SB_DQ<2>")
		)
		(pad "246" smd rect
			(at 2.050034 27.62504 270)
			(size 0.519938 1.4986)
			(layers "F.Cu" "F.Mask" "F.Paste")
			(net "GND")
		)
		(pad "247" smd rect
			(at 2.050034 28.474924 270)
			(size 0.519938 1.4986)
			(layers "F.Cu" "F.Mask" "F.Paste")
			(net "M_A_CPU1_SB_DQ<3>")
		)
		(pad "248" smd rect
			(at 2.050034 29.325062 270)
			(size 0.519938 1.4986)
			(layers "F.Cu" "F.Mask" "F.Paste")
			(net "GND")
		)
		(pad "249" smd rect
			(at 2.050034 30.174946 270)
			(size 0.519938 1.4986)
			(layers "F.Cu" "F.Mask" "F.Paste")
			(net "M_A_CPU1_SB_DQS_DN<5>")
		)
		(pad "250" smd rect
			(at 2.050034 31.025084 270)
			(size 0.519938 1.4986)
			(layers "F.Cu" "F.Mask" "F.Paste")
			(net "M_A_CPU1_SB_DQS_DP<5>")
		)
		(pad "251" smd rect
			(at 2.050034 31.874968 270)
			(size 0.519938 1.4986)
			(layers "F.Cu" "F.Mask" "F.Paste")
			(net "GND")
		)
		(pad "252" smd rect
			(at 2.050034 32.725106 270)
			(size 0.519938 1.4986)
			(layers "F.Cu" "F.Mask" "F.Paste")
			(net "M_A_CPU1_SB_DQ<6>")
		)
		(pad "253" smd rect
			(at 2.050034 33.57499 270)
			(size 0.519938 1.4986)
			(layers "F.Cu" "F.Mask" "F.Paste")
			(net "GND")
		)
		(pad "254" smd rect
			(at 2.050034 34.425128 270)
			(size 0.519938 1.4986)
			(layers "F.Cu" "F.Mask" "F.Paste")
			(net "M_A_CPU1_SB_DQ<7>")
		)
		(pad "255" smd rect
			(at 2.050034 35.275012 270)
			(size 0.519938 1.4986)
			(layers "F.Cu" "F.Mask" "F.Paste")
			(net "GND")
		)
		(pad "256" smd rect
			(at 2.050034 36.124896 270)
			(size 0.519938 1.4986)
			(layers "F.Cu" "F.Mask" "F.Paste")
			(net "M_A_CPU1_SB_DQ<10>")
		)
		(pad "257" smd rect
			(at 2.050034 36.975034 270)
			(size 0.519938 1.4986)
			(layers "F.Cu" "F.Mask" "F.Paste")
			(net "GND")
		)
		(pad "258" smd rect
			(at 2.050034 37.824918 270)
			(size 0.519938 1.4986)
			(layers "F.Cu" "F.Mask" "F.Paste")
			(net "M_A_CPU1_SB_DQ<11>")
		)
		(pad "259" smd rect
			(at 2.050034 38.675056 270)
			(size 0.519938 1.4986)
			(layers "F.Cu" "F.Mask" "F.Paste")
			(net "GND")
		)
		(pad "260" smd rect
			(at 2.050034 39.52494 270)
			(size 0.519938 1.4986)
			(layers "F.Cu" "F.Mask" "F.Paste")
			(net "M_A_CPU1_SB_DQS_DN<6>")
		)
		(pad "261" smd rect
			(at 2.050034 40.375078 270)
			(size 0.519938 1.4986)
			(layers "F.Cu" "F.Mask" "F.Paste")
			(net "M_A_CPU1_SB_DQS_DP<6>")
		)
		(pad "262" smd rect
			(at 2.050034 41.224962 270)
			(size 0.519938 1.4986)
			(layers "F.Cu" "F.Mask" "F.Paste")
			(net "GND")
		)
		(pad "263" smd rect
			(at 2.050034 42.0751 270)
			(size 0.519938 1.4986)
			(layers "F.Cu" "F.Mask" "F.Paste")
			(net "M_A_CPU1_SB_DQ<14>")
		)
		(pad "264" smd rect
			(at 2.050034 42.924984 270)
			(size 0.519938 1.4986)
			(layers "F.Cu" "F.Mask" "F.Paste")
			(net "GND")
		)
		(pad "265" smd rect
			(at 2.050034 43.775122 270)
			(size 0.519938 1.4986)
			(layers "F.Cu" "F.Mask" "F.Paste")
			(net "M_A_CPU1_SB_DQ<15>")
		)
		(pad "266" smd rect
			(at 2.050034 44.625006 270)
			(size 0.519938 1.4986)
			(layers "F.Cu" "F.Mask" "F.Paste")
			(net "GND")
		)
		(pad "267" smd rect
			(at 2.050034 45.47489 270)
			(size 0.519938 1.4986)
			(layers "F.Cu" "F.Mask" "F.Paste")
			(net "M_A_CPU1_SB_DQ<18>")
		)
		(pad "268" smd rect
			(at 2.050034 46.325028 270)
			(size 0.519938 1.4986)
			(layers "F.Cu" "F.Mask" "F.Paste")
			(net "GND")
		)
		(pad "269" smd rect
			(at 2.050034 47.174912 270)
			(size 0.519938 1.4986)
			(layers "F.Cu" "F.Mask" "F.Paste")
			(net "M_A_CPU1_SB_DQ<19>")
		)
		(pad "270" smd rect
			(at 2.050034 48.02505 270)
			(size 0.519938 1.4986)
			(layers "F.Cu" "F.Mask" "F.Paste")
			(net "GND")
		)
		(pad "271" smd rect
			(at 2.050034 48.874934 270)
			(size 0.519938 1.4986)
			(layers "F.Cu" "F.Mask" "F.Paste")
			(net "M_A_CPU1_SB_DQS_DN<7>")
		)
		(pad "272" smd rect
			(at 2.050034 49.725072 270)
			(size 0.519938 1.4986)
			(layers "F.Cu" "F.Mask" "F.Paste")
			(net "M_A_CPU1_SB_DQS_DP<7>")
		)
		(pad "273" smd rect
			(at 2.050034 50.574956 270)
			(size 0.519938 1.4986)
			(layers "F.Cu" "F.Mask" "F.Paste")
			(net "GND")
		)
		(pad "274" smd rect
			(at 2.050034 51.425094 270)
			(size 0.519938 1.4986)
			(layers "F.Cu" "F.Mask" "F.Paste")
			(net "M_A_CPU1_SB_DQ<22>")
		)
	)
)
